# T6G (Grand Teton) — schematic netlist excerpt (pin names and nets, part order shuffled) for the footprints in the layout excerpt that follows; sources: Cadence DE-HDL packaged netlist, KiCad conversion of 04192023_DAF0TMB3IC0_F0TG_MB_C_brd_V02_OCP.brd

R363  Q_RES  1K 1% CHIP  pkg 0402LF  page 161 : A = PVDD11_S3_P0 ; B = SMB_APML_CPU0_SCL
PC525  Q_CAPP  470UF 2.5V 20% SPCAP  pkg SMLF  page 225 : A = PVDD11_S3_P1 ; B = GND

(kicad_pcb
	(version 20260206)
	(generator "pcbnew")
	(generator_version "10.0")
	(general
		(thickness 1.6)
		(legacy_teardrops no)
	)
	(paper "A4")
	(title_block
		(title "04192023_DAF0TMB3IC0_F0TG_MB_C_brd_V02_OCP.brd")
		(comment 1 "Grand Teton / footprints 7416-7417 of 8354")
	)
	(layers
		(0 "F.Cu" signal "TOP")
		(4 "In1.Cu" signal "GND")
		(6 "In2.Cu" signal "IN1")
		(8 "In3.Cu" signal "GND1")
		(10 "In4.Cu" signal "IN2")
		(12 "In5.Cu" signal "GND2")
		(14 "In6.Cu" signal "IN3")
		(16 "In7.Cu" signal "GND3")
		(18 "In8.Cu" signal "VCC")
		(20 "In9.Cu" signal "VCC1")
		(22 "In10.Cu" signal "GND4")
		(24 "In11.Cu" signal "IN4")
		(26 "In12.Cu" signal "GND5")
		(28 "In13.Cu" signal "IN5")
		(30 "In14.Cu" signal "GND6")
		(32 "In15.Cu" signal "IN6")
		(34 "In16.Cu" signal "GND7")
		(2 "B.Cu" signal "BOTTOM")
		(9 "F.Adhes" user "F.Adhesive")
		(11 "B.Adhes" user "B.Adhesive")
		(13 "F.Paste" user "Package Geometry/Pastemask Top")
		(15 "B.Paste" user "Package Geometry/Pastemask Bottom")
		(5 "F.SilkS" user "Ref Des/Silkscreen Top")
		(7 "B.SilkS" user "Ref Des/Silkscreen Bottom")
		(1 "F.Mask" user "Board Geometry/Soldermask Top")
		(3 "B.Mask" user "Board Geometry/Soldermask Bottom")
		(17 "Dwgs.User" user "User.Drawings")
		(19 "Cmts.User" user "User.Comments")
		(21 "Eco1.User" user "User.Eco1")
		(23 "Eco2.User" user "User.Eco2")
		(25 "Edge.Cuts" user "Board Geometry/Outline")
		(27 "Margin" user)
		(31 "F.CrtYd" user "Package Geometry/Place Bound Top")
		(29 "B.CrtYd" user "Package Geometry/Place Bound Bottom")
		(35 "F.Fab" user "Ref Des/Assembly Top")
		(33 "B.Fab" user "Ref Des/Assembly Bottom")
	)
	(footprint ""
		(layer "B.Cu")
		(at 237.617 -250.571)
		(property "Reference" "R363"
			(at 0 0 0)
			(layer "B.SilkS")
			(hide yes)
			(effects
				(font
					(size 1.27 1.27)
				)
				(justify mirror)
			)
		)
		(property "Value" ""
			(at 0 0 0)
			(layer "B.Fab")
			(effects
				(font
					(size 1.27 1.27)
				)
				(justify mirror)
			)
		)
		(duplicate_pad_numbers_are_jumpers no)
		(fp_line
			(start -0.7874 -0.4064)
			(end -0.7874 0.4064)
			(stroke
				(width 0.1524)
				(type default)
			)
			(layer "B.SilkS")
		)
		(fp_line
			(start -0.7874 0.4064)
			(end 0.7874 0.4064)
			(stroke
				(width 0.1524)
				(type default)
			)
			(layer "B.SilkS")
		)
		(fp_line
			(start 0.7874 -0.4064)
			(end -0.7874 -0.4064)
			(stroke
				(width 0.1524)
				(type default)
			)
			(layer "B.SilkS")
		)
		(fp_line
			(start 0.7874 0.4064)
			(end 0.7874 -0.4064)
			(stroke
				(width 0.1524)
				(type default)
			)
			(layer "B.SilkS")
		)
		(fp_line
			(start -0.67945 -0.3048)
			(end -0.67945 0.3048)
			(stroke
				(width 0.1)
				(type default)
			)
			(layer "B.Fab")
		)
		(fp_line
			(start -0.67945 0.3048)
			(end -0.120396 0.3048)
			(stroke
				(width 0.1)
				(type default)
			)
			(layer "B.Fab")
		)
		(fp_line
			(start -0.12065 -0.3048)
			(end -0.67945 -0.3048)
			(stroke
				(width 0.1)
				(type default)
			)
			(layer "B.Fab")
		)
		(fp_line
			(start -0.12065 -0.2794)
			(end -0.12065 -0.3048)
			(stroke
				(width 0.1)
				(type default)
			)
			(layer "B.Fab")
		)
		(fp_line
			(start -0.120396 0.2794)
			(end 0.12065 0.2794)
			(stroke
				(width 0.1)
				(type default)
			)
			(layer "B.Fab")
		)
		(fp_line
			(start -0.120396 0.3048)
			(end -0.120396 0.2794)
			(stroke
				(width 0.1)
				(type default)
			)
			(layer "B.Fab")
		)
		(fp_line
			(start 0.12065 -0.305054)
			(end 0.12065 -0.2794)
			(stroke
				(width 0.1)
				(type default)
			)
			(layer "B.Fab")
		)
		(fp_line
			(start 0.12065 -0.2794)
			(end -0.12065 -0.2794)
			(stroke
				(width 0.1)
				(type default)
			)
			(layer "B.Fab")
		)
		(fp_line
			(start 0.12065 0.2794)
			(end 0.12065 0.3048)
			(stroke
				(width 0.1)
				(type default)
			)
			(layer "B.Fab")
		)
		(fp_line
			(start 0.12065 0.3048)
			(end 0.67945 0.3048)
			(stroke
				(width 0.1)
				(type default)
			)
			(layer "B.Fab")
		)
		(fp_line
			(start 0.67945 -0.305054)
			(end 0.12065 -0.305054)
			(stroke
				(width 0.1)
				(type default)
			)
			(layer "B.Fab")
		)
		(fp_line
			(start 0.67945 0.3048)
			(end 0.67945 -0.305054)
			(stroke
				(width 0.1)
				(type default)
			)
			(layer "B.Fab")
		)
		(pad "1" smd circle
			(at 0.40005 0 180)
			(size 0 0)
			(layers "B.Cu" "B.Mask" "B.Paste")
			(net "PVDD11_S3_P0")
		)
		(pad "2" smd circle
			(at -0.40005 0 180)
			(size 0 0)
			(layers "B.Cu" "B.Mask" "B.Paste")
			(net "SMB_APML_CPU0_SCL")
		)
	)
	(footprint ""
		(layer "B.Cu")
		(at 182.948834 -344.199972 -90)
		(property "Reference" "PC525"
			(at 7.610856 -3.388106 270)
			(unlocked yes)
			(layer "B.SilkS")
			(effects
				(font
					(size 0.7874 0.5842)
					(thickness 0.1524)
				)
				(justify left mirror)
			)
		)
		(property "Value" ""
			(at 0 0 90)
			(layer "B.Fab")
			(effects
				(font
					(size 1.27 1.27)
				)
				(justify mirror)
			)
		)
		(duplicate_pad_numbers_are_jumpers no)
		(fp_line
			(start -4.533392 2.249932)
			(end 4.533392 2.249932)
			(stroke
				(width 0.1524)
				(type default)
			)
			(layer "B.SilkS")
		)
		(fp_line
			(start 4.533392 2.249932)
			(end 4.533392 -2.249932)
			(stroke
				(width 0.1524)
				(type default)
			)
			(layer "B.SilkS")
		)
		(fp_line
			(start -4.533392 -2.249932)
			(end -4.533392 2.249932)
			(stroke
				(width 0.1524)
				(type default)
			)
			(layer "B.SilkS")
		)
		(fp_line
			(start 4.533392 -2.249932)
			(end -4.533392 -2.249932)
			(stroke
				(width 0.1524)
				(type default)
			)
			(layer "B.SilkS")
		)
		(fp_rect
			(start 5.39242 2.326132)
			(end 4.533392 -2.326132)
			(stroke
				(width 0)
				(type default)
			)
			(fill yes)
			(layer "B.SilkS")
		)
		(fp_line
			(start -3.750056 2.249932)
			(end 3.750056 2.249932)
			(stroke
				(width 0.1)
				(type default)
			)
			(layer "B.Fab")
		)
		(fp_line
			(start 3.750056 2.249932)
			(end 3.750056 -2.249932)
			(stroke
				(width 0.1)
				(type default)
			)
			(layer "B.Fab")
		)
		(fp_line
			(start -3.750056 -2.249932)
			(end -3.750056 2.249932)
			(stroke
				(width 0.1)
				(type default)
			)
			(layer "B.Fab")
		)
		(fp_line
			(start 3.750056 -2.249932)
			(end -3.750056 -2.249932)
			(stroke
				(width 0.1)
				(type default)
			)
			(layer "B.Fab")
		)
		(fp_text user "-"
			(at -4.658868 2.486914 270)
			(unlocked yes)
			(layer "B.SilkS")
			(effects
				(font
					(size 1.905 1.4224)
					(thickness 0.1524)
				)
				(justify left mirror)
			)
		)
		(fp_text user "+"
			(at 6.322314 0.786384 180)
			(unlocked yes)
			(layer "B.SilkS")
			(effects
				(font
					(size 1.905 1.4224)
					(thickness 0.1524)
				)
				(justify left mirror)
			)
		)
		(fp_text user "+"
			(at 6.322314 0.786384 180)
			(unlocked yes)
			(layer "B.Fab")
			(effects
				(font
					(size 1.905 1.4224)
					(thickness 0.1524)
				)
				(justify left mirror)
			)
		)
		(fp_text user "-"
			(at -4.8514 -0.14605 270)
			(unlocked yes)
			(layer "B.Fab")
			(effects
				(font
					(size 1.905 1.4224)
					(thickness 0.1524)
				)
				(justify left mirror)
			)
		)
		(pad "1" smd rect
			(at 3.199892 0 90)
			(size 2.413 2.8194)
			(layers "B.Cu" "B.Mask" "B.Paste")
			(net "PVDD11_S3_P1")
		)
		(pad "2" smd rect
			(at -3.199892 0 90)
			(size 2.413 2.8194)
			(layers "B.Cu" "B.Mask" "B.Paste")
			(net "GND")
		)
	)
)
